(kicad_pcb
	(version 20241229)
	(generator "pcbnew")
	(generator_version "9.0")
	(general
		(thickness 1.711)
		(legacy_teardrops no)
	)
	(paper "A4")
	(title_block
		(title "Antmicro Baseboard for Jetson AGX Thor")
		(date "2026-02-18")
		(rev "1.1.0")
		(company "Antmicro Ltd")
		(comment 1 "www.antmicro.com")
		(comment 9 "footprints 1123-1126 of 1170")
	)
	(layers
		(0 "F.Cu" signal)
		(4 "In1.Cu" signal)
		(6 "In2.Cu" signal)
		(8 "In3.Cu" signal)
		(10 "In4.Cu" jumper)
		(12 "In5.Cu" signal)
		(14 "In6.Cu" signal)
		(16 "In7.Cu" signal)
		(18 "In8.Cu" signal)
		(2 "B.Cu" signal)
		(9 "F.Adhes" user "F.Adhesive")
		(11 "B.Adhes" user "B.Adhesive")
		(13 "F.Paste" user)
		(15 "B.Paste" user)
		(5 "F.SilkS" user "F.Silkscreen")
		(7 "B.SilkS" user "B.Silkscreen")
		(1 "F.Mask" user)
		(3 "B.Mask" user)
		(17 "Dwgs.User" user "User.Drawings")
		(19 "Cmts.User" user "User.Comments")
		(21 "Eco1.User" user "User.Eco1")
		(23 "Eco2.User" user "User.Eco2")
		(25 "Edge.Cuts" user)
		(27 "Margin" user)
		(31 "F.CrtYd" user "F.Courtyard")
		(29 "B.CrtYd" user "B.Courtyard")
		(35 "F.Fab" user)
		(33 "B.Fab" user)
	)
	(footprint "antmicro-footprints:SOT-23-6"
		(layer "B.Cu")
		(at 179.286 76.046 90)
		(property "Reference" "U64"
			(at -1.14 -2.68 90)
			(layer "B.SilkS")
			(effects
				(font
					(size 0.7 0.7)
					(thickness 0.15)
				)
				(justify right top mirror)
			)
		)
		(property "Value" "LTC4412IS6"
			(at -1.75 -2.693 90)
			(layer "B.Fab")
			(effects
				(font
					(size 0.7 0.7)
					(thickness 0.15)
				)
				(justify right top mirror)
			)
		)
		(property "Datasheet" "https://www.analog.com/media/en/technical-documentation/data-sheets/4412fb.pdf"
			(at 0 0.057 90)
			(layer "B.Fab")
			(hide yes)
			(effects
				(font
					(size 1.27 1.27)
					(thickness 0.15)
				)
				(justify mirror)
			)
		)
		(property "Description" "Ideal diode controller"
			(at 0 0.057 90)
			(layer "B.Fab")
			(hide yes)
			(effects
				(font
					(size 1.27 1.27)
					(thickness 0.15)
				)
				(justify mirror)
			)
		)
		(property "MPN" "LTC4412IS6#TRMPBF"
			(at 0 0 270)
			(unlocked yes)
			(layer "B.Fab")
			(hide yes)
			(effects
				(font
					(size 1 1)
					(thickness 0.15)
				)
				(justify mirror)
			)
		)
		(property "Manufacturer" "Analog Devices"
			(at 0 0 270)
			(unlocked yes)
			(layer "B.Fab")
			(hide yes)
			(effects
				(font
					(size 1 1)
					(thickness 0.15)
				)
				(justify mirror)
			)
		)
		(property "Author" "Antmicro"
			(at 0 0 270)
			(unlocked yes)
			(layer "B.Fab")
			(hide yes)
			(effects
				(font
					(size 1 1)
					(thickness 0.15)
				)
				(justify mirror)
			)
		)
		(property "License" "Apache-2.0"
			(at 0 0 270)
			(unlocked yes)
			(layer "B.Fab")
			(hide yes)
			(effects
				(font
					(size 1 1)
					(thickness 0.15)
				)
				(justify mirror)
			)
		)
		(sheetname "/Power/")
		(sheetfile "power.kicad_sch")
		(attr smd)
		(fp_line
			(start 1.45 -0.643)
			(end 1.45 -0.343)
			(stroke
				(width 0.12)
				(type solid)
			)
			(layer "B.SilkS")
		)
		(fp_line
			(start 1.3 -0.643)
			(end 1.45 -0.643)
			(stroke
				(width 0.12)
				(type solid)
			)
			(layer "B.SilkS")
		)
		(fp_line
			(start -1.45 -0.643)
			(end -1.45 -0.343)
			(stroke
				(width 0.12)
				(type solid)
			)
			(layer "B.SilkS")
		)
		(fp_line
			(start 1.45 0.757)
			(end 1.45 0.457)
			(stroke
				(width 0.12)
				(type solid)
			)
			(layer "B.SilkS")
		)
		(fp_line
			(start 1.3 0.757)
			(end 1.45 0.757)
			(stroke
				(width 0.12)
				(type solid)
			)
			(layer "B.SilkS")
		)
		(fp_line
			(start -1.3 0.757)
			(end -1.45 0.757)
			(stroke
				(width 0.12)
				(type solid)
			)
			(layer "B.SilkS")
		)
		(fp_line
			(start -1.45 0.757)
			(end -1.45 0.457)
			(stroke
				(width 0.12)
				(type solid)
			)
			(layer "B.SilkS")
		)
		(fp_rect
			(start -1.55 1.85)
			(end 1.55 -1.75)
			(stroke
				(width 0.05)
				(type solid)
			)
			(fill no)
			(layer "B.CrtYd")
		)
		(fp_line
			(start 1.5 -0.643)
			(end -1.5 -0.643)
			(stroke
				(width 0.1)
				(type solid)
			)
			(layer "B.Fab")
		)
		(fp_line
			(start -1.5 -0.643)
			(end -1.5 0.757)
			(stroke
				(width 0.1)
				(type solid)
			)
			(layer "B.Fab")
		)
		(fp_line
			(start 1.5 0.757)
			(end 1.5 -0.643)
			(stroke
				(width 0.1)
				(type solid)
			)
			(layer "B.Fab")
		)
		(fp_line
			(start -1.5 0.757)
			(end 1.5 0.757)
			(stroke
				(width 0.1)
				(type solid)
			)
			(layer "B.Fab")
		)
		(fp_text user "."
			(at -1.4 -2.486 90)
			(layer "B.SilkS")
			(effects
				(font
					(size 1 1)
					(thickness 0.15)
				)
				(justify mirror)
			)
		)
		(fp_text user "License: Apache-2.0"
			(at -1.75 -6.5 90)
			(layer "B.Fab")
			(effects
				(font
					(size 0.7 0.7)
					(thickness 0.15)
				)
				(justify right top mirror)
			)
		)
		(fp_text user "Author: Antmicro"
			(at -1.829 -5.25 90)
			(layer "B.Fab")
			(effects
				(font
					(size 0.7 0.7)
					(thickness 0.15)
				)
				(justify right top mirror)
			)
		)
		(fp_text user "${REFERENCE}"
			(at -1.75 -4 90)
			(layer "B.Fab")
			(effects
				(font
					(size 0.7 0.7)
					(thickness 0.15)
				)
				(justify right top mirror)
			)
		)
		(pad "1" smd roundrect
			(at -0.954 -1.1 90)
			(size 0.55 1)
			(layers "B.Cu" "B.Mask" "B.Paste")
			(roundrect_rratio 0.15)
			(net 904 "+20V")
			(pinfunction "IN")
			(pintype "power_in")
		)
		(pad "2" smd roundrect
			(at -0.003 -1.1 90)
			(size 0.55 1)
			(layers "B.Cu" "B.Mask" "B.Paste")
			(roundrect_rratio 0.15)
			(net 1 "GND")
			(pinfunction "GND")
			(pintype "power_in")
		)
		(pad "3" smd roundrect
			(at 0.947 -1.1 90)
			(size 0.55 1)
			(layers "B.Cu" "B.Mask" "B.Paste")
			(roundrect_rratio 0.15)
			(net 1 "GND")
			(pinfunction "CTL")
			(pintype "input")
		)
		(pad "4" smd roundrect
			(at 0.947 1.214 90)
			(size 0.55 1)
			(layers "B.Cu" "B.Mask" "B.Paste")
			(roundrect_rratio 0.15)
			(net 1227 "unconnected-(U64-STAT-Pad4)")
			(pinfunction "STAT")
			(pintype "output+no_connect")
		)
		(pad "5" smd roundrect
			(at -0.003 1.214 90)
			(size 0.55 1)
			(layers "B.Cu" "B.Mask" "B.Paste")
			(roundrect_rratio 0.15)
			(net 1203 "Net-(Q25-G)")
			(pinfunction "GATE")
			(pintype "output")
		)
		(pad "6" smd roundrect
			(at -0.954 1.214 90)
			(size 0.55 1)
			(layers "B.Cu" "B.Mask" "B.Paste")
			(roundrect_rratio 0.15)
			(net 525 "/Power/USBPD2_HV")
			(pinfunction "SENSE")
			(pintype "input")
		)
	)
	(footprint "antmicro-footprints:R_0402_1005Metric"
		(layer "B.Cu")
		(at 111.12 120.59)
		(descr "Resistor SMD 0402")
		(tags "resistor SMD 0402")
		(property "Reference" "R218"
			(at -3.72 -0.39 0)
			(layer "B.SilkS")
			(effects
				(font
					(size 0.7 0.7)
					(thickness 0.15)
				)
				(justify right top mirror)
			)
		)
		(property "Value" "R_0R_0402"
			(at -1.011843 -1.772047 0)
			(layer "B.Fab")
			(effects
				(font
					(size 0.7 0.7)
					(thickness 0.15)
				)
				(justify right top mirror)
			)
		)
		(property "Datasheet" "https://industrial.panasonic.com/cdbs/www-data/pdf/RDA0000/AOA0000C301.pdf"
			(at 0 0 0)
			(layer "B.Fab")
			(hide yes)
			(effects
				(font
					(size 1.27 1.27)
					(thickness 0.15)
				)
				(justify mirror)
			)
		)
		(property "Description" "SMD Chip Resistor, Jumper, 0 ohm, 100 mW, 0402 [1005 Metric], Thick Film, General Purpose"
			(at 0 0 0)
			(layer "B.Fab")
			(hide yes)
			(effects
				(font
					(size 1.27 1.27)
					(thickness 0.15)
				)
				(justify mirror)
			)
		)
		(property "MPN" "ERJ2GE0R00X"
			(at 0 0 180)
			(unlocked yes)
			(layer "B.Fab")
			(hide yes)
			(effects
				(font
					(size 1 1)
					(thickness 0.15)
				)
				(justify mirror)
			)
		)
		(property "Manufacturer" "Panasonic"
			(at 0 0 180)
			(unlocked yes)
			(layer "B.Fab")
			(hide yes)
			(effects
				(font
					(size 1 1)
					(thickness 0.15)
				)
				(justify mirror)
			)
		)
		(property "License" "Apache-2.0"
			(at 0 0 180)
			(unlocked yes)
			(layer "B.Fab")
			(hide yes)
			(effects
				(font
					(size 1 1)
					(thickness 0.15)
				)
				(justify mirror)
			)
		)
		(property "Val" "0R"
			(at 0 0 180)
			(unlocked yes)
			(layer "B.Fab")
			(hide yes)
			(effects
				(font
					(size 1 1)
					(thickness 0.15)
				)
				(justify mirror)
			)
		)
		(property "Tolerance" "~"
			(at 0 0 180)
			(unlocked yes)
			(layer "B.Fab")
			(hide yes)
			(effects
				(font
					(size 1 1)
					(thickness 0.15)
				)
				(justify mirror)
			)
		)
		(property "Current" "1A"
			(at 0 0 180)
			(unlocked yes)
			(layer "B.Fab")
			(hide yes)
			(effects
				(font
					(size 1 1)
					(thickness 0.15)
				)
				(justify mirror)
			)
		)
		(property "Author" "Antmicro"
			(at 0 0 180)
			(unlocked yes)
			(layer "B.Fab")
			(hide yes)
			(effects
				(font
					(size 1 1)
					(thickness 0.15)
				)
				(justify mirror)
			)
		)
		(property "Public" "False"
			(at 0 0 180)
			(unlocked yes)
			(layer "B.Fab")
			(hide yes)
			(effects
				(font
					(size 1 1)
					(thickness 0.15)
				)
				(justify mirror)
			)
		)
		(sheetname "/M.2/")
		(sheetfile "m2.kicad_sch")
		(attr smd)
		(fp_rect
			(start -0.925 0.47)
			(end 0.925 -0.47)
			(stroke
				(width 0.05)
				(type default)
			)
			(fill no)
			(layer "B.CrtYd")
		)
		(fp_rect
			(start -0.5 0.25)
			(end 0.5 -0.25)
			(stroke
				(width 0.15)
				(type solid)
			)
			(fill no)
			(layer "B.Fab")
		)
		(fp_text user "${REFERENCE}"
			(at -0.95 -3.168 0)
			(layer "B.Fab")
			(effects
				(font
					(size 0.7 0.7)
					(thickness 0.15)
				)
				(justify right top mirror)
			)
		)
		(fp_text user "License: Apache-2.0"
			(at -0.95 -5.169 0)
			(layer "B.Fab")
			(effects
				(font
					(size 0.7 0.7)
					(thickness 0.15)
				)
				(justify right top mirror)
			)
		)
		(fp_text user "Author: Antmicro"
			(at -0.95 -4.169 0)
			(layer "B.Fab")
			(effects
				(font
					(size 0.7 0.7)
					(thickness 0.15)
				)
				(justify right top mirror)
			)
		)
		(pad "1" smd roundrect
			(at -0.48 0)
			(size 0.59 0.64)
			(layers "B.Cu" "B.Mask" "B.Paste")
			(roundrect_rratio 0.25)
			(net 653 "/M.2/USB3.D+")
			(pintype "passive")
		)
		(pad "2" smd roundrect
			(at 0.48 0)
			(size 0.59 0.64)
			(layers "B.Cu" "B.Mask" "B.Paste")
			(roundrect_rratio 0.25)
			(net 272 "/M.2/WIFI_BT_USB_D_P")
			(pintype "passive")
		)
	)
	(footprint "antmicro-footprints:R_0402_1005Metric"
		(layer "B.Cu")
		(at 194.8 87.8 90)
		(descr "Resistor SMD 0402")
		(tags "resistor SMD 0402")
		(property "Reference" "R383"
			(at -3.7 -0.4 90)
			(layer "B.SilkS")
			(effects
				(font
					(size 0.7 0.7)
					(thickness 0.15)
				)
				(justify right top mirror)
			)
		)
		(property "Value" "R_0R_0402"
			(at -1.011843 -1.772047 90)
			(layer "B.Fab")
			(effects
				(font
					(size 0.7 0.7)
					(thickness 0.15)
				)
				(justify right top mirror)
			)
		)
		(property "Datasheet" "https://industrial.panasonic.com/cdbs/www-data/pdf/RDA0000/AOA0000C301.pdf"
			(at 0 0 90)
			(layer "B.Fab")
			(hide yes)
			(effects
				(font
					(size 1.27 1.27)
					(thickness 0.15)
				)
				(justify mirror)
			)
		)
		(property "Description" "SMD Chip Resistor, Jumper, 0 ohm, 100 mW, 0402 [1005 Metric], Thick Film, General Purpose"
			(at 0 0 90)
			(layer "B.Fab")
			(hide yes)
			(effects
				(font
					(size 1.27 1.27)
					(thickness 0.15)
				)
				(justify mirror)
			)
		)
		(property "MPN" "ERJ2GE0R00X"
			(at 0 0 270)
			(unlocked yes)
			(layer "B.Fab")
			(hide yes)
			(effects
				(font
					(size 1 1)
					(thickness 0.15)
				)
				(justify mirror)
			)
		)
		(property "Manufacturer" "Panasonic"
			(at 0 0 270)
			(unlocked yes)
			(layer "B.Fab")
			(hide yes)
			(effects
				(font
					(size 1 1)
					(thickness 0.15)
				)
				(justify mirror)
			)
		)
		(property "License" "Apache-2.0"
			(at 0 0 270)
			(unlocked yes)
			(layer "B.Fab")
			(hide yes)
			(effects
				(font
					(size 1 1)
					(thickness 0.15)
				)
				(justify mirror)
			)
		)
		(property "Author" "Antmicro"
			(at 0 0 270)
			(unlocked yes)
			(layer "B.Fab")
			(hide yes)
			(effects
				(font
					(size 1 1)
					(thickness 0.15)
				)
				(justify mirror)
			)
		)
		(property "Val" "0R"
			(at 0 0 270)
			(unlocked yes)
			(layer "B.Fab")
			(hide yes)
			(effects
				(font
					(size 1 1)
					(thickness 0.15)
				)
				(justify mirror)
			)
		)
		(property "Tolerance" "~"
			(at 0 0 270)
			(unlocked yes)
			(layer "B.Fab")
			(hide yes)
			(effects
				(font
					(size 1 1)
					(thickness 0.15)
				)
				(justify mirror)
			)
		)
		(property "Current" "1A"
			(at 0 0 270)
			(unlocked yes)
			(layer "B.Fab")
			(hide yes)
			(effects
				(font
					(size 1 1)
					(thickness 0.15)
				)
				(justify mirror)
			)
		)
		(sheetname "/USB Debug, PD/")
		(sheetfile "usb_debug_pd.kicad_sch")
		(attr smd)
		(fp_rect
			(start -0.925 0.47)
			(end 0.925 -0.47)
			(stroke
				(width 0.05)
				(type default)
			)
			(fill no)
			(layer "B.CrtYd")
		)
		(fp_rect
			(start -0.5 0.25)
			(end 0.5 -0.25)
			(stroke
				(width 0.15)
				(type solid)
			)
			(fill no)
			(layer "B.Fab")
		)
		(fp_text user "${REFERENCE}"
			(at -0.95 -3.168 90)
			(layer "B.Fab")
			(effects
				(font
					(size 0.7 0.7)
					(thickness 0.15)
				)
				(justify right top mirror)
			)
		)
		(fp_text user "Author: Antmicro"
			(at -0.95 -4.169 90)
			(layer "B.Fab")
			(effects
				(font
					(size 0.7 0.7)
					(thickness 0.15)
				)
				(justify right top mirror)
			)
		)
		(fp_text user "License: Apache-2.0"
			(at -0.95 -5.169 90)
			(layer "B.Fab")
			(effects
				(font
					(size 0.7 0.7)
					(thickness 0.15)
				)
				(justify right top mirror)
			)
		)
		(pad "1" smd roundrect
			(at -0.48 0 90)
			(size 0.59 0.64)
			(layers "B.Cu" "B.Mask" "B.Paste")
			(roundrect_rratio 0.25)
			(net 532 "/USB Debug, PD/SCK")
			(pintype "passive")
		)
		(pad "2" smd roundrect
			(at 0.48 0 90)
			(size 0.59 0.64)
			(layers "B.Cu" "B.Mask" "B.Paste")
			(roundrect_rratio 0.25)
			(net 941 "/USB Debug, PD/PDC_SCLK")
			(pintype "passive")
		)
	)
	(footprint "antmicro-footprints:C_0402_1005Metric"
		(layer "B.Cu")
		(at 212.8 95.409002 90)
		(descr "Capacitor SMD 0402")
		(tags "capacitor SMD 0402")
		(property "Reference" "C322"
			(at -3.7 -0.4 90)
			(layer "B.SilkS")
			(effects
				(font
					(size 0.7 0.7)
					(thickness 0.15)
				)
				(justify right top mirror)
			)
		)
		(property "Value" "C_100n_0402"
			(at -1.022927 -2.155213 90)
			(layer "B.Fab")
			(effects
				(font
					(size 0.7 0.7)
					(thickness 0.15)
				)
				(justify right top mirror)
			)
		)
		(property "Datasheet" "https://www.murata.com/products/productdetail?partno=GRM155R61H104KE14%23"
			(at 0 0 90)
			(layer "B.Fab")
			(hide yes)
			(effects
				(font
					(size 1.27 1.27)
					(thickness 0.15)
				)
				(justify mirror)
			)
		)
		(property "Description" "SMD Multilayer Ceramic Capacitor, 0.1 µF, 50 V, 0402 [1005 Metric], ± 10%, X5R, GRM Series"
			(at 0 0 90)
			(layer "B.Fab")
			(hide yes)
			(effects
				(font
					(size 1.27 1.27)
					(thickness 0.15)
				)
				(justify mirror)
			)
		)
		(property "Manufacturer" "Murata"
			(at 0 0 270)
			(unlocked yes)
			(layer "B.Fab")
			(hide yes)
			(effects
				(font
					(size 1 1)
					(thickness 0.15)
				)
				(justify mirror)
			)
		)
		(property "MPN" "GRM155R61H104KE14D"
			(at 0 0 270)
			(unlocked yes)
			(layer "B.Fab")
			(hide yes)
			(effects
				(font
					(size 1 1)
					(thickness 0.15)
				)
				(justify mirror)
			)
		)
		(property "Val" "100n"
			(at 0 0 270)
			(unlocked yes)
			(layer "B.Fab")
			(hide yes)
			(effects
				(font
					(size 1 1)
					(thickness 0.15)
				)
				(justify mirror)
			)
		)
		(property "License" "Apache-2.0"
			(at 0 0 270)
			(unlocked yes)
			(layer "B.Fab")
			(hide yes)
			(effects
				(font
					(size 1 1)
					(thickness 0.15)
				)
				(justify mirror)
			)
		)
		(property "Author" "Antmicro"
			(at 0 0 270)
			(unlocked yes)
			(layer "B.Fab")
			(hide yes)
			(effects
				(font
					(size 1 1)
					(thickness 0.15)
				)
				(justify mirror)
			)
		)
		(property "Voltage" "50V"
			(at 0 0 270)
			(unlocked yes)
			(layer "B.Fab")
			(hide yes)
			(effects
				(font
					(size 1 1)
					(thickness 0.15)
				)
				(justify mirror)
			)
		)
		(property "Dielectric" "X5R"
			(at 0 0 270)
			(unlocked yes)
			(layer "B.Fab")
			(hide yes)
			(effects
				(font
					(size 1 1)
					(thickness 0.15)
				)
				(justify mirror)
			)
		)
		(sheetname "/SoM_IO2/")
		(sheetfile "som_io2.kicad_sch")
		(attr smd)
		(fp_rect
			(start -0.925 0.47)
			(end 0.925 -0.47)
			(stroke
				(width 0.05)
				(type default)
			)
			(fill no)
			(layer "B.CrtYd")
		)
		(fp_line
			(start 0.504 -0.248)
			(end -0.494 -0.248)
			(stroke
				(width 0.15)
				(type solid)
			)
			(layer "B.Fab")
		)
		(fp_line
			(start -0.494 -0.248)
			(end -0.494 0.25)
			(stroke
				(width 0.15)
				(type solid)
			)
			(layer "B.Fab")
		)
		(fp_line
			(start 0.504 0.25)
			(end 0.504 -0.248)
			(stroke
				(width 0.15)
				(type solid)
			)
			(layer "B.Fab")
		)
		(fp_line
			(start -0.494 0.25)
			(end 0.504 0.25)
			(stroke
				(width 0.15)
				(type solid)
			)
			(layer "B.Fab")
		)
		(fp_text user "License: Apache-2.0"
			(at -0.939 -5.799 90)
			(layer "B.Fab")
			(effects
				(font
					(size 0.7 0.7)
					(thickness 0.15)
				)
				(justify right top mirror)
			)
		)
		(fp_text user "${REFERENCE}"
			(at -0.939 -4.599 90)
			(layer "B.Fab")
			(effects
				(font
					(size 0.7 0.7)
					(thickness 0.15)
				)
				(justify right top mirror)
			)
		)
		(fp_text user "Author: Antmicro"
			(at -0.939 -3.399 90)
			(layer "B.Fab")
			(effects
				(font
					(size 0.7 0.7)
					(thickness 0.15)
				)
				(justify right top mirror)
			)
		)
		(pad "1" smd roundrect
			(at -0.48 0 90)
			(size 0.59 0.64)
			(layers "B.Cu" "B.Mask" "B.Paste")
			(roundrect_rratio 0.25)
			(net 1088 "/SoM_IO2/DP0.AUX_C+")
			(pintype "passive")
		)
		(pad "2" smd roundrect
			(at 0.48 0 90)
			(size 0.59 0.64)
			(layers "B.Cu" "B.Mask" "B.Paste")
			(roundrect_rratio 0.25)
			(net 635 "/SoM_IO2/DP0.AUX+")
			(pintype "passive")
		)
	)
)
